(kicad_pcb
	(version 20241229)
	(generator "pcbnew")
	(generator_version "9.0")
	(general
		(thickness 1.61)
		(legacy_teardrops no)
	)
	(paper "A3")
	(title_block
		(title "RDIMM DDR5 Tester")
		(date "2026-05-21")
		(rev "2.2.0")
		(company "Antmicro")
		(comment 9 "footprints 378-380 of 796")
	)
	(layers
		(0 "F.Cu" signal)
		(4 "In1.Cu" power)
		(6 "In2.Cu" mixed)
		(8 "In3.Cu" power)
		(10 "In4.Cu" mixed)
		(12 "In5.Cu" power)
		(14 "In6.Cu" mixed)
		(16 "In7.Cu" power)
		(18 "In8.Cu" power)
		(20 "In9.Cu" mixed)
		(22 "In10.Cu" power)
		(2 "B.Cu" signal)
		(9 "F.Adhes" user "F.Adhesive")
		(11 "B.Adhes" user "B.Adhesive")
		(13 "F.Paste" user)
		(15 "B.Paste" user)
		(5 "F.SilkS" user "F.Silkscreen")
		(7 "B.SilkS" user "B.Silkscreen")
		(1 "F.Mask" user)
		(3 "B.Mask" user)
		(17 "Dwgs.User" user "User.Drawings")
		(19 "Cmts.User" user "User.Comments")
		(21 "Eco1.User" user "User.Eco1")
		(23 "Eco2.User" user "User.Eco2")
		(25 "Edge.Cuts" user)
		(27 "Margin" user)
		(31 "F.CrtYd" user "F.Courtyard")
		(29 "B.CrtYd" user "B.Courtyard")
		(35 "F.Fab" user)
		(33 "B.Fab" user)
	)
	(footprint "antmicro-footprints:SW_DIP_SPSTx03_Slide_Copal_CVS-03xB_W5.9mm_P1mm"
		(layer "F.Cu")
		(at 149.3 181.75)
		(descr "SMD 3x-dip-switch SPST Copal_CVS-03xB, Slide, row spacing 5.9 mm (232 mils), body size  (see http://www.nidec-copal-electronics.com/e/catalog/switch/cvs.pdf)")
		(tags "SMD DIP Switch SPST Slide")
		(property "Reference" "SW1"
			(at 0.725 3.55 0)
			(layer "F.SilkS")
			(effects
				(font
					(size 0.7 0.7)
					(thickness 0.15)
				)
				(justify left bottom)
			)
		)
		(property "Value" "CVS-03B"
			(at 0.248 4.799 0)
			(layer "F.Fab")
			(effects
				(font
					(size 0.7 0.7)
					(thickness 0.15)
				)
				(justify left bottom)
			)
		)
		(property "Datasheet" "https://www.mouser.com/datasheet/2/972/cvs-1827291.pdf"
			(at 0 0 0)
			(layer "F.Fab")
			(hide yes)
			(effects
				(font
					(size 1.27 1.27)
					(thickness 0.15)
				)
			)
		)
		(property "MPN" "CVS-03B"
			(at 0 0 0)
			(unlocked yes)
			(layer "F.Fab")
			(hide yes)
			(effects
				(font
					(size 1 1)
					(thickness 0.15)
				)
			)
		)
		(property "Manufacturer" "Nidec Components"
			(at 0 0 0)
			(unlocked yes)
			(layer "F.Fab")
			(hide yes)
			(effects
				(font
					(size 1 1)
					(thickness 0.15)
				)
			)
		)
		(property "Author" "Antmicro"
			(at 0 0 0)
			(unlocked yes)
			(layer "F.Fab")
			(hide yes)
			(effects
				(font
					(size 1 1)
					(thickness 0.15)
				)
			)
		)
		(property "License" "Apache-2.0"
			(at 0 0 0)
			(unlocked yes)
			(layer "F.Fab")
			(hide yes)
			(effects
				(font
					(size 1 1)
					(thickness 0.15)
				)
			)
		)
		(property ki_fp_filters "SW?DIP?x2*")
		(sheetname "/PCIe connector/")
		(sheetfile "pcie-connector.kicad_sch")
		(attr smd)
		(fp_line
			(start -1.51 -2.411)
			(end 1.61 -2.411)
			(stroke
				(width 0.15)
				(type solid)
			)
			(layer "F.SilkS")
		)
		(fp_line
			(start -1.51 2.41)
			(end 1.61 2.41)
			(stroke
				(width 0.15)
				(type solid)
			)
			(layer "F.SilkS")
		)
		(fp_circle
			(center -3.33 -1.641)
			(end -3.281 -1.641)
			(stroke
				(width 0.15)
				(type solid)
			)
			(fill yes)
			(layer "F.SilkS")
		)
		(fp_rect
			(start -3.56 -2.5)
			(end 3.66 2.49)
			(stroke
				(width 0.05)
				(type solid)
			)
			(fill no)
			(layer "F.CrtYd")
		)
		(fp_line
			(start -2.301 -1)
			(end -1.301 -2)
			(stroke
				(width 0.15)
				(type solid)
			)
			(layer "F.Fab")
		)
		(fp_line
			(start -2.301 1.999)
			(end -2.301 -1)
			(stroke
				(width 0.15)
				(type solid)
			)
			(layer "F.Fab")
		)
		(fp_line
			(start -1.301 -2)
			(end 2.398 -2)
			(stroke
				(width 0.15)
				(type solid)
			)
			(layer "F.Fab")
		)
		(fp_line
			(start -0.951 -1.25)
			(end -0.951 -0.75)
			(stroke
				(width 0.15)
				(type solid)
			)
			(layer "F.Fab")
		)
		(fp_line
			(start -0.951 -1.151)
			(end -0.285 -1.151)
			(stroke
				(width 0.15)
				(type solid)
			)
			(layer "F.Fab")
		)
		(fp_line
			(start -0.951 -1.051)
			(end -0.285 -1.051)
			(stroke
				(width 0.15)
				(type solid)
			)
			(layer "F.Fab")
		)
		(fp_line
			(start -0.951 -0.952)
			(end -0.285 -0.952)
			(stroke
				(width 0.15)
				(type solid)
			)
			(layer "F.Fab")
		)
		(fp_line
			(start -0.951 -0.85)
			(end -0.285 -0.85)
			(stroke
				(width 0.15)
				(type solid)
			)
			(layer "F.Fab")
		)
		(fp_line
			(start -0.951 -0.75)
			(end 1.05 -0.75)
			(stroke
				(width 0.15)
				(type solid)
			)
			(layer "F.Fab")
		)
		(fp_line
			(start -0.951 -0.25)
			(end -0.951 0.247)
			(stroke
				(width 0.15)
				(type solid)
			)
			(layer "F.Fab")
		)
		(fp_line
			(start -0.951 -0.15)
			(end -0.285 -0.15)
			(stroke
				(width 0.15)
				(type solid)
			)
			(layer "F.Fab")
		)
		(fp_line
			(start -0.951 -0.053)
			(end -0.285 -0.053)
			(stroke
				(width 0.15)
				(type solid)
			)
			(layer "F.Fab")
		)
		(fp_line
			(start -0.951 0.05)
			(end -0.285 0.05)
			(stroke
				(width 0.15)
				(type solid)
			)
			(layer "F.Fab")
		)
		(fp_line
			(start -0.951 0.147)
			(end -0.285 0.147)
			(stroke
				(width 0.15)
				(type solid)
			)
			(layer "F.Fab")
		)
		(fp_line
			(start -0.951 0.247)
			(end 1.05 0.247)
			(stroke
				(width 0.15)
				(type solid)
			)
			(layer "F.Fab")
		)
		(fp_line
			(start -0.951 0.747)
			(end -0.951 1.249)
			(stroke
				(width 0.15)
				(type solid)
			)
			(layer "F.Fab")
		)
		(fp_line
			(start -0.951 0.847)
			(end -0.285 0.847)
			(stroke
				(width 0.15)
				(type solid)
			)
			(layer "F.Fab")
		)
		(fp_line
			(start -0.951 0.949)
			(end -0.285 0.949)
			(stroke
				(width 0.15)
				(type solid)
			)
			(layer "F.Fab")
		)
		(fp_line
			(start -0.951 1.05)
			(end -0.285 1.05)
			(stroke
				(width 0.15)
				(type solid)
			)
			(layer "F.Fab")
		)
		(fp_line
			(start -0.951 1.148)
			(end -0.285 1.148)
			(stroke
				(width 0.15)
				(type solid)
			)
			(layer "F.Fab")
		)
		(fp_line
			(start -0.951 1.249)
			(end 1.05 1.249)
			(stroke
				(width 0.15)
				(type solid)
			)
			(layer "F.Fab")
		)
		(fp_line
			(start -0.285 -1.25)
			(end -0.285 -0.75)
			(stroke
				(width 0.15)
				(type solid)
			)
			(layer "F.Fab")
		)
		(fp_line
			(start -0.285 -0.25)
			(end -0.285 0.247)
			(stroke
				(width 0.15)
				(type solid)
			)
			(layer "F.Fab")
		)
		(fp_line
			(start -0.285 0.747)
			(end -0.285 1.249)
			(stroke
				(width 0.15)
				(type solid)
			)
			(layer "F.Fab")
		)
		(fp_line
			(start 1.05 -1.25)
			(end -0.951 -1.25)
			(stroke
				(width 0.15)
				(type solid)
			)
			(layer "F.Fab")
		)
		(fp_line
			(start 1.05 -0.75)
			(end 1.05 -1.25)
			(stroke
				(width 0.15)
				(type solid)
			)
			(layer "F.Fab")
		)
		(fp_line
			(start 1.05 -0.25)
			(end -0.951 -0.25)
			(stroke
				(width 0.15)
				(type solid)
			)
			(layer "F.Fab")
		)
		(fp_line
			(start 1.05 0.247)
			(end 1.05 -0.25)
			(stroke
				(width 0.15)
				(type solid)
			)
			(layer "F.Fab")
		)
		(fp_line
			(start 1.05 0.747)
			(end -0.951 0.747)
			(stroke
				(width 0.15)
				(type solid)
			)
			(layer "F.Fab")
		)
		(fp_line
			(start 1.05 1.249)
			(end 1.05 0.747)
			(stroke
				(width 0.15)
				(type solid)
			)
			(layer "F.Fab")
		)
		(fp_line
			(start 2.398 -2)
			(end 2.398 1.999)
			(stroke
				(width 0.15)
				(type solid)
			)
			(layer "F.Fab")
		)
		(fp_line
			(start 2.398 1.999)
			(end -2.301 1.999)
			(stroke
				(width 0.15)
				(type solid)
			)
			(layer "F.Fab")
		)
		(fp_text user "Author: Antmicro"
			(at -3.56 7.999 0)
			(layer "F.Fab")
			(effects
				(font
					(size 0.7 0.7)
					(thickness 0.15)
				)
				(justify left bottom)
			)
		)
		(fp_text user "${REFERENCE}"
			(at -3.56 9.199 0)
			(layer "F.Fab")
			(effects
				(font
					(size 0.7 0.7)
					(thickness 0.15)
				)
				(justify left bottom)
			)
		)
		(fp_text user "on"
			(at -1.44 0.72 90)
			(layer "F.Fab")
			(effects
				(font
					(size 0.7 0.7)
					(thickness 0.15)
				)
				(justify left bottom)
			)
		)
		(fp_text user "License: Apache-2.0"
			(at -3.56 10.399 0)
			(layer "F.Fab")
			(effects
				(font
					(size 0.7 0.7)
					(thickness 0.15)
				)
				(justify left bottom)
			)
		)
		(pad "1" smd rect
			(at -2.899 -1)
			(size 1.2 0.5)
			(layers "F.Cu" "F.Mask" "F.Paste")
			(net 174 "/PCIe connector/PRSNT#1")
			(pinfunction "1")
			(pintype "passive")
		)
		(pad "2" smd rect
			(at -2.899 0)
			(size 1.2 0.5)
			(layers "F.Cu" "F.Mask" "F.Paste")
			(net 174 "/PCIe connector/PRSNT#1")
			(pinfunction "2")
			(pintype "passive")
		)
		(pad "3" smd rect
			(at -2.899 0.997)
			(size 1.2 0.5)
			(layers "F.Cu" "F.Mask" "F.Paste")
			(net 174 "/PCIe connector/PRSNT#1")
			(pinfunction "3")
			(pintype "passive")
		)
		(pad "4" smd rect
			(at 2.999 0.997)
			(size 1.2 0.5)
			(layers "F.Cu" "F.Mask" "F.Paste")
			(net 591 "/PCIe connector/x8")
			(pinfunction "4")
			(pintype "passive")
		)
		(pad "5" smd rect
			(at 2.999 0)
			(size 1.2 0.5)
			(layers "F.Cu" "F.Mask" "F.Paste")
			(net 176 "/PCIe connector/x4")
			(pinfunction "5")
			(pintype "passive")
		)
		(pad "6" smd rect
			(at 2.999 -1)
			(size 1.2 0.5)
			(layers "F.Cu" "F.Mask" "F.Paste")
			(net 175 "/PCIe connector/x1")
			(pinfunction "6")
			(pintype "passive")
		)
		(pad "7" smd rect
			(at -2.101 -2)
			(size 0.7 0.7)
			(layers "F.Cu" "F.Mask" "F.Paste")
			(net 1 "GND")
			(pinfunction "7")
			(pintype "power_in")
		)
		(pad "7" smd rect
			(at -2.101 1.999)
			(size 0.7 0.7)
			(layers "F.Cu" "F.Mask" "F.Paste")
			(net 1 "GND")
			(pinfunction "7")
			(pintype "power_in")
		)
		(pad "7" smd rect
			(at 2.201 -2)
			(size 0.7 0.7)
			(layers "F.Cu" "F.Mask" "F.Paste")
			(net 1 "GND")
			(pinfunction "7")
			(pintype "power_in")
		)
		(pad "7" smd rect
			(at 2.201 1.999)
			(size 0.7 0.7)
			(layers "F.Cu" "F.Mask" "F.Paste")
			(net 1 "GND")
			(pinfunction "7")
			(pintype "power_in")
		)
	)
	(footprint "antmicro-footprints:USON-10_2.5x1mm_P0.5mm"
		(layer "F.Cu")
		(at 113.530499 175.7685 180)
		(descr "USON-10 2.5x1mm_ Pitch 0.5mm")
		(tags "USON-10 2.5x1mm Pitch 0.5mm")
		(property "Reference" "U48"
			(at -1.799501 0.1985 90)
			(layer "F.SilkS")
			(effects
				(font
					(size 0.7 0.7)
					(thickness 0.15)
				)
				(justify right bottom)
			)
		)
		(property "Value" "TPD4E05U06QDQARQ1"
			(at 0.018 2.499 0)
			(layer "F.Fab")
			(effects
				(font
					(size 0.7 0.7)
					(thickness 0.15)
				)
				(justify right bottom)
			)
		)
		(property "Datasheet" "https://www.ti.com/lit/ds/symlink/tpd4e05u06-q1.pdf?HQS=dis-mous-null-mousermode-dsf-pf-null-wwe&ts=1663591265741&ref_url=https%253A%252F%252Fwww.mouser.com%252F"
			(at 0 0 180)
			(layer "F.Fab")
			(hide yes)
			(effects
				(font
					(size 1.27 1.27)
					(thickness 0.15)
				)
			)
		)
		(property "Manufacturer" "Texas Instruments"
			(at 0 0 180)
			(unlocked yes)
			(layer "F.Fab")
			(hide yes)
			(effects
				(font
					(size 1 1)
					(thickness 0.15)
				)
			)
		)
		(property "MPN" "TPD4E05U06QDQARQ1"
			(at 0 0 180)
			(unlocked yes)
			(layer "F.Fab")
			(hide yes)
			(effects
				(font
					(size 1 1)
					(thickness 0.15)
				)
			)
		)
		(property "Author" "Antmicro"
			(at 0 0 180)
			(unlocked yes)
			(layer "F.Fab")
			(hide yes)
			(effects
				(font
					(size 1 1)
					(thickness 0.15)
				)
			)
		)
		(property "License" "Apache-2.0"
			(at 0 0 180)
			(unlocked yes)
			(layer "F.Fab")
			(hide yes)
			(effects
				(font
					(size 1 1)
					(thickness 0.15)
				)
			)
		)
		(sheetname "/HDMI + SD Card/")
		(sheetfile "hdmi-sd-card.kicad_sch")
		(attr smd)
		(fp_line
			(start 0.498 1.398)
			(end -0.5 1.398)
			(stroke
				(width 0.15)
				(type solid)
			)
			(layer "F.SilkS")
		)
		(fp_line
			(start 0.498 -1.401)
			(end -0.5 -1.401)
			(stroke
				(width 0.15)
				(type solid)
			)
			(layer "F.SilkS")
		)
		(fp_circle
			(center -0.68 -1.27)
			(end -0.63 -1.27)
			(stroke
				(width 0.15)
				(type solid)
			)
			(fill yes)
			(layer "F.SilkS")
		)
		(fp_rect
			(start -0.8 -1.5)
			(end 0.8 1.499)
			(stroke
				(width 0.05)
				(type solid)
			)
			(fill no)
			(layer "F.CrtYd")
		)
		(fp_line
			(start 0.498 -1.25)
			(end 0.498 1.249)
			(stroke
				(width 0.15)
				(type solid)
			)
			(layer "F.Fab")
		)
		(fp_line
			(start 0.498 -1.25)
			(end -0.25 -1.25)
			(stroke
				(width 0.15)
				(type solid)
			)
			(layer "F.Fab")
		)
		(fp_line
			(start -0.25 -1.25)
			(end -0.5 -1)
			(stroke
				(width 0.15)
				(type solid)
			)
			(layer "F.Fab")
		)
		(fp_line
			(start -0.5 1.249)
			(end 0.498 1.249)
			(stroke
				(width 0.15)
				(type solid)
			)
			(layer "F.Fab")
		)
		(fp_line
			(start -0.5 -1)
			(end -0.5 1.249)
			(stroke
				(width 0.15)
				(type solid)
			)
			(layer "F.Fab")
		)
		(fp_text user "License: Apache-2.0"
			(at -0.802 6.9 180)
			(layer "F.Fab")
			(effects
				(font
					(size 0.7 0.7)
					(thickness 0.15)
				)
				(justify left bottom)
			)
		)
		(fp_text user "Author: Antmicro"
			(at -0.802 5.7 180)
			(layer "F.Fab")
			(effects
				(font
					(size 0.7 0.7)
					(thickness 0.15)
				)
				(justify left bottom)
			)
		)
		(fp_text user "${REFERENCE}"
			(at -0.802 4.498 180)
			(layer "F.Fab")
			(effects
				(font
					(size 0.7 0.7)
					(thickness 0.15)
				)
				(justify left bottom)
			)
		)
		(pad "1" smd roundrect
			(at -0.387 -1 90)
			(size 0.25 0.55)
			(layers "F.Cu" "F.Mask" "F.Paste")
			(roundrect_rratio 0.25)
			(net 467 "/HDMI + SD Card/HDMI_OUT_C.SCL")
			(pintype "passive")
		)
		(pad "2" smd roundrect
			(at -0.387 -0.5 90)
			(size 0.25 0.55)
			(layers "F.Cu" "F.Mask" "F.Paste")
			(roundrect_rratio 0.25)
			(net 468 "/HDMI + SD Card/HDMI_OUT_C.SDA")
			(pintype "passive")
		)
		(pad "3" smd roundrect
			(at -0.387 0 90)
			(size 0.4 0.55)
			(layers "F.Cu" "F.Mask" "F.Paste")
			(roundrect_rratio 0.25)
			(net 1 "GND")
			(pintype "power_in")
		)
		(pad "4" smd roundrect
			(at -0.387 0.498 90)
			(size 0.25 0.55)
			(layers "F.Cu" "F.Mask" "F.Paste")
			(roundrect_rratio 0.25)
			(net 8 "/HDMI + SD Card/HDMI_CONN_5V")
			(pintype "passive")
		)
		(pad "5" smd roundrect
			(at -0.387 0.998 90)
			(size 0.25 0.55)
			(layers "F.Cu" "F.Mask" "F.Paste")
			(roundrect_rratio 0.25)
			(net 605 "/HDMI + SD Card/HDMI0.HPD")
			(pintype "passive")
		)
		(pad "6" smd roundrect
			(at 0.385 0.998 90)
			(size 0.25 0.55)
			(layers "F.Cu" "F.Mask" "F.Paste")
			(roundrect_rratio 0.25)
			(net 605 "/HDMI + SD Card/HDMI0.HPD")
			(pintype "passive")
		)
		(pad "7" smd roundrect
			(at 0.385 0.498 90)
			(size 0.25 0.55)
			(layers "F.Cu" "F.Mask" "F.Paste")
			(roundrect_rratio 0.25)
			(net 8 "/HDMI + SD Card/HDMI_CONN_5V")
			(pintype "passive")
		)
		(pad "8" smd roundrect
			(at 0.385 0 90)
			(size 0.4 0.55)
			(layers "F.Cu" "F.Mask" "F.Paste")
			(roundrect_rratio 0.25)
			(net 1 "GND")
			(pintype "passive")
		)
		(pad "9" smd roundrect
			(at 0.385 -0.5 90)
			(size 0.25 0.55)
			(layers "F.Cu" "F.Mask" "F.Paste")
			(roundrect_rratio 0.25)
			(net 468 "/HDMI + SD Card/HDMI_OUT_C.SDA")
			(pintype "passive")
		)
		(pad "10" smd roundrect
			(at 0.385 -1 90)
			(size 0.25 0.55)
			(layers "F.Cu" "F.Mask" "F.Paste")
			(roundrect_rratio 0.25)
			(net 467 "/HDMI + SD Card/HDMI_OUT_C.SCL")
			(pintype "passive")
		)
	)
	(footprint "antmicro-footprints:R_0402_1005Metric"
		(layer "B.Cu")
		(at 141.124499 169.399 -90)
		(descr "Resistor SMD 0402")
		(tags "resistor SMD 0402")
		(property "Reference" "R56"
			(at -4.045 -0.505501 90)
			(layer "B.SilkS")
			(effects
				(font
					(size 0.7 0.7)
					(thickness 0.15)
				)
				(justify left bottom mirror)
			)
		)
		(property "Value" "R_22R_0402"
			(at -1.011843 -1.772047 90)
			(layer "B.Fab")
			(effects
				(font
					(size 0.7 0.7)
					(thickness 0.15)
				)
				(justify left bottom mirror)
			)
		)
		(property "Datasheet" "https://www.bourns.com/docs/product-datasheets/cr.pdf"
			(at 0 0 270)
			(layer "F.Fab")
			(hide yes)
			(effects
				(font
					(size 1.27 1.27)
					(thickness 0.15)
				)
			)
		)
		(property "Manufacturer" "Bourns"
			(at 0 0 270)
			(unlocked yes)
			(layer "B.Fab")
			(hide yes)
			(effects
				(font
					(size 1 1)
					(thickness 0.15)
				)
				(justify mirror)
			)
		)
		(property "MPN" "CR0402-FX-22R0GLF"
			(at 0 0 270)
			(unlocked yes)
			(layer "B.Fab")
			(hide yes)
			(effects
				(font
					(size 1 1)
					(thickness 0.15)
				)
				(justify mirror)
			)
		)
		(property "Val" "22R"
			(at 0 0 270)
			(unlocked yes)
			(layer "B.Fab")
			(hide yes)
			(effects
				(font
					(size 1 1)
					(thickness 0.15)
				)
				(justify mirror)
			)
		)
		(property "License" "Apache-2.0"
			(at 0 0 270)
			(unlocked yes)
			(layer "B.Fab")
			(hide yes)
			(effects
				(font
					(size 1 1)
					(thickness 0.15)
				)
				(justify mirror)
			)
		)
		(property "Author" "Antmicro"
			(at 0 0 270)
			(unlocked yes)
			(layer "B.Fab")
			(hide yes)
			(effects
				(font
					(size 1 1)
					(thickness 0.15)
				)
				(justify mirror)
			)
		)
		(property "Tolerance" "1%"
			(at 0 0 270)
			(unlocked yes)
			(layer "B.Fab")
			(hide yes)
			(effects
				(font
					(size 1 1)
					(thickness 0.15)
				)
				(justify mirror)
			)
		)
		(sheetname "/Debug FTDI + VNA/")
		(sheetfile "debug-ftdi.kicad_sch")
		(attr smd exclude_from_bom dnp)
		(fp_rect
			(start -0.925 0.47)
			(end 0.925 -0.47)
			(stroke
				(width 0.05)
				(type default)
			)
			(fill no)
			(layer "B.CrtYd")
		)
		(fp_rect
			(start -0.5 0.25)
			(end 0.5 -0.25)
			(stroke
				(width 0.15)
				(type solid)
			)
			(fill no)
			(layer "B.Fab")
		)
		(fp_text user "License: Apache-2.0"
			(at -0.95 -5.169 90)
			(layer "B.Fab")
			(effects
				(font
					(size 0.7 0.7)
					(thickness 0.15)
				)
				(justify left bottom mirror)
			)
		)
		(fp_text user "Author: Antmicro"
			(at -0.95 -4.169 90)
			(layer "B.Fab")
			(effects
				(font
					(size 0.7 0.7)
					(thickness 0.15)
				)
				(justify left bottom mirror)
			)
		)
		(fp_text user "${REFERENCE}"
			(at -0.95 -3.168 90)
			(layer "B.Fab")
			(effects
				(font
					(size 0.7 0.7)
					(thickness 0.15)
				)
				(justify left bottom mirror)
			)
		)
		(pad "1" smd roundrect
			(at -0.48 0 270)
			(size 0.59 0.64)
			(layers "B.Cu" "B.Mask" "B.Paste")
			(roundrect_rratio 0.25)
			(net 379 "/Debug FTDI + VNA/BDBUS0")
			(pintype "passive")
		)
		(pad "2" smd roundrect
			(at 0.48 0 270)
			(size 0.59 0.64)
			(layers "B.Cu" "B.Mask" "B.Paste")
			(roundrect_rratio 0.25)
			(net 388 "/Debug FTDI + VNA/AUX.TCK")
			(pintype "passive")
		)
	)
)
